# Bryce Canyon_Rear_Drive_Plane_Board_Stackup.xlsx — PCB Test Plan_HVM(0-90) (pcb-stackup)
|  | Board vendor give feedback of quantity in yellow columns based on the AQL table or description. |  |  |  |  |  |  |  |  |  |  |  |  |  |  |
|  | Wiwynn PM give feedback in blue columns |  |  |  |  |  |  |  |  |  |  |  |  |  |  |
| Person to be informed : PCB vendor, EE, SI, PM, PSM, Buyer, SQM |  |  |  |  |  |  |  |  |  |  |  |  |  |  |  |
| Simple flow : SI (test requirements) -> PM/AM (Total PCBS demand) -> Buyer -> Board Vendor (yellow column feedback) -> Buyer -> Person to be informed (Check and Track) |  |  |  |  |  |  |  |  |  |  |  |  |  |  |  |
| PO(purchase order) : If there are many POs for this PCB, 1st sample quantity is based on 1st PO, 2nd sample quantity is based on 2nd PO. |  |  |  |  |  |  |  |  |  |  |  |  |  |  |  |
| Project Name | PCB name | PCB# (1XXXX-XX) | Product Stage | Batch# | PCB Vendor | PCBs Demand | Delta-L Coupon (PCB Vendor) | Delta-L Coupon (3rd Party Lab) | Impedance Coupon (PCB Vendor) | In-board trace correlation (PCB Vendor) | X-section Analysis (PCB Vendor) | IST (3rd Party Lab) | Resin Void (PCB Vendor) | IPC-6012D (3rd Party Lab) | Note 1 |
| Bryce Canyon | RDPB | 16317-1 | HVM(0-90 days) | N/A |  |  | Yes | Yes | Yes | Yes | Yes | Yes | No | Yes | Need Test? (Yes, No) |
| Tracking Code On Both Of Coupon And PCB |  |  |  |  |  |  | Follow rules of board vendor | Follow rules of board vendor | Follow rules of board vendor | Follow rules of board vendor | Follow rules of board vendor | Follow rules of board vendor |  | Follow rules of board vendor |  |
| Test Item Acceptance Criteria |  |  |  |  |  |  | Failure Rate ≦0.3% | Failure Rate ≦0.3% | Cpk≧1.0 | Fail : 0 Variation ≦5% | Cpk≧1.0 | Fail: 0 |  | Per IPC |  |
| Test Item Sampling Quantity |  |  |  |  |  |  | AQL 1, level 1 | 30 pcs | AQL 1, level 1 | AQL 1, level 1 | 5 pcs/production lot, with max total of 30 pcs | 5 pcs/production lot, with max total of 30 pcs |  | max total of 3 pcs |  |
| Test Time (working days) |  |  |  |  |  |  | 5 | 5 | 5 | 5 | 15 | 20+ |  | 15 |  |
| Test Item Shipping Quantity |  |  |  |  |  |  |  | 30 pcs |  |  |  | 5 pcs/production lot, with max total of 30 pcs |  | 3 pcs |  |
| Shipping Address |  |  |  |  |  |  |  | 8F, 90, Sec. 1, Xintai 5th Rd., Xizhi Dist., New Taipei City 22102, Taiwan, R.O.C. |  |  |  | 8F, 90, Sec. 1, Xintai 5th Rd., Xizhi Dist., New Taipei City 22102, Taiwan, R.O.C. |  | 8F, 90, Sec. 1, Xintai 5th Rd., Xizhi Dist., New Taipei City 22102, Taiwan, R.O.C. |  |
| Receiver Name |  |  |  |  |  |  |  | Karol Lai |  |  |  | Karol Lai |  | Karol Lai |  |
| Receiver Phone# |  |  |  |  |  |  |  | 886-2-6612-7507 |  |  |  | 886-2-6612-7507 |  | Direct: 886(2) 6612-7507 |  |
